# T6G (Grand Teton) — schematic netlist excerpt (pin names and nets, part order shuffled) for the footprints in the layout excerpt that follows; sources: Cadence DE-HDL packaged netlist, KiCad conversion of 04192023_DAF0TMB3IC0_F0TG_MB_C_brd_V02_OCP.brd

C877  Q_CAP_DIFFBUS  DIFF BUS_0.22UF 6.3V 20% X6S  pkg C0201  page 64 : \1\ = P5E_CPU0_P3_TX_C_DP<12> ; \2\ = P5E_CPU0_P3_TX_DP<12>
C6703  Q_CAP_DIFFBUS  DIFF BUS_0.22UF 6.3V 20% X6S  pkg C0201  page 341 : \1\ = P5E_CPU1_P2_TX_BUF_C_DP<5> ; \2\ = P5E_CPU1_P2_TX_BUF_DP<5>
PC2166  Q_CAP  0.047UF 25V 10% X7R  pkg C0402  page 141 : A = P12V_OCP_SS_2 ; B = GND

(kicad_pcb
	(version 20260206)
	(generator "pcbnew")
	(generator_version "10.0")
	(general
		(thickness 1.6)
		(legacy_teardrops no)
	)
	(paper "A4")
	(title_block
		(title "04192023_DAF0TMB3IC0_F0TG_MB_C_brd_V02_OCP.brd")
		(comment 1 "Grand Teton / footprints 4856-4858 of 8354")
	)
	(layers
		(0 "F.Cu" signal "TOP")
		(4 "In1.Cu" signal "GND")
		(6 "In2.Cu" signal "IN1")
		(8 "In3.Cu" signal "GND1")
		(10 "In4.Cu" signal "IN2")
		(12 "In5.Cu" signal "GND2")
		(14 "In6.Cu" signal "IN3")
		(16 "In7.Cu" signal "GND3")
		(18 "In8.Cu" signal "VCC")
		(20 "In9.Cu" signal "VCC1")
		(22 "In10.Cu" signal "GND4")
		(24 "In11.Cu" signal "IN4")
		(26 "In12.Cu" signal "GND5")
		(28 "In13.Cu" signal "IN5")
		(30 "In14.Cu" signal "GND6")
		(32 "In15.Cu" signal "IN6")
		(34 "In16.Cu" signal "GND7")
		(2 "B.Cu" signal "BOTTOM")
		(9 "F.Adhes" user "F.Adhesive")
		(11 "B.Adhes" user "B.Adhesive")
		(13 "F.Paste" user "Package Geometry/Pastemask Top")
		(15 "B.Paste" user "Package Geometry/Pastemask Bottom")
		(5 "F.SilkS" user "Ref Des/Silkscreen Top")
		(7 "B.SilkS" user "Ref Des/Silkscreen Bottom")
		(1 "F.Mask" user "Board Geometry/Soldermask Top")
		(3 "B.Mask" user "Board Geometry/Soldermask Bottom")
		(17 "Dwgs.User" user "User.Drawings")
		(19 "Cmts.User" user "User.Comments")
		(21 "Eco1.User" user "User.Eco1")
		(23 "Eco2.User" user "User.Eco2")
		(25 "Edge.Cuts" user "Board Geometry/Outline")
		(27 "Margin" user)
		(31 "F.CrtYd" user "Package Geometry/Place Bound Top")
		(29 "B.CrtYd" user "Package Geometry/Place Bound Bottom")
		(35 "F.Fab" user "Ref Des/Assembly Top")
		(33 "B.Fab" user "Ref Des/Assembly Bottom")
	)
	(footprint ""
		(layer "F.Cu")
		(at 131.099306 -408.517344 -90)
		(property "Reference" "C6703"
			(at 0 0 270)
			(layer "F.SilkS")
			(hide yes)
			(effects
				(font
					(size 1.27 1.27)
				)
			)
		)
		(property "Value" ""
			(at 0 0 270)
			(layer "F.Fab")
			(effects
				(font
					(size 1.27 1.27)
				)
			)
		)
		(duplicate_pad_numbers_are_jumpers no)
		(fp_line
			(start -0.299974 0.150114)
			(end -0.299974 -0.150114)
			(stroke
				(width 0.1)
				(type default)
			)
			(layer "F.Fab")
		)
		(fp_line
			(start 0.299974 0.150114)
			(end -0.299974 0.150114)
			(stroke
				(width 0.1)
				(type default)
			)
			(layer "F.Fab")
		)
		(fp_line
			(start -0.299974 -0.150114)
			(end 0.299974 -0.150114)
			(stroke
				(width 0.1)
				(type default)
			)
			(layer "F.Fab")
		)
		(fp_line
			(start 0.299974 -0.150114)
			(end 0.299974 0.150114)
			(stroke
				(width 0.1)
				(type default)
			)
			(layer "F.Fab")
		)
		(pad "1" smd rect
			(at -0.2667 0 270)
			(size 0.3048 0.381)
			(layers "F.Cu" "F.Mask" "F.Paste")
			(net "P5E_CPU1_P2_TX_BUF_C_DP<5>")
		)
		(pad "2" smd rect
			(at 0.2667 0 270)
			(size 0.3048 0.381)
			(layers "F.Cu" "F.Mask" "F.Paste")
			(net "P5E_CPU1_P2_TX_BUF_DP<5>")
		)
	)
	(footprint ""
		(layer "F.Cu")
		(at 388.213092 -378.95403 -90)
		(property "Reference" "C877"
			(at 0 0 270)
			(layer "F.SilkS")
			(hide yes)
			(effects
				(font
					(size 1.27 1.27)
				)
			)
		)
		(property "Value" ""
			(at 0 0 270)
			(layer "F.Fab")
			(effects
				(font
					(size 1.27 1.27)
				)
			)
		)
		(duplicate_pad_numbers_are_jumpers no)
		(fp_line
			(start -0.299974 0.150114)
			(end -0.299974 -0.150114)
			(stroke
				(width 0.1)
				(type default)
			)
			(layer "F.Fab")
		)
		(fp_line
			(start 0.299974 0.150114)
			(end -0.299974 0.150114)
			(stroke
				(width 0.1)
				(type default)
			)
			(layer "F.Fab")
		)
		(fp_line
			(start -0.299974 -0.150114)
			(end 0.299974 -0.150114)
			(stroke
				(width 0.1)
				(type default)
			)
			(layer "F.Fab")
		)
		(fp_line
			(start 0.299974 -0.150114)
			(end 0.299974 0.150114)
			(stroke
				(width 0.1)
				(type default)
			)
			(layer "F.Fab")
		)
		(pad "1" smd rect
			(at -0.2667 0 270)
			(size 0.3048 0.381)
			(layers "F.Cu" "F.Mask" "F.Paste")
			(net "P5E_CPU0_P3_TX_C_DP<12>")
		)
		(pad "2" smd rect
			(at 0.2667 0 270)
			(size 0.3048 0.381)
			(layers "F.Cu" "F.Mask" "F.Paste")
			(net "P5E_CPU0_P3_TX_DP<12>")
		)
	)
	(footprint ""
		(layer "F.Cu")
		(at 66.369438 -31.887922 90)
		(property "Reference" "PC2166"
			(at 0 0 90)
			(layer "F.SilkS")
			(hide yes)
			(effects
				(font
					(size 1.27 1.27)
				)
			)
		)
		(property "Value" ""
			(at 0 0 90)
			(layer "F.Fab")
			(effects
				(font
					(size 1.27 1.27)
				)
			)
		)
		(duplicate_pad_numbers_are_jumpers no)
		(fp_line
			(start 0.7874 -0.4064)
			(end 0.7874 0.4064)
			(stroke
				(width 0.1524)
				(type default)
			)
			(layer "F.SilkS")
		)
		(fp_line
			(start -0.7874 -0.4064)
			(end 0.7874 -0.4064)
			(stroke
				(width 0.1524)
				(type default)
			)
			(layer "F.SilkS")
		)
		(fp_line
			(start 0.7874 0.4064)
			(end -0.7874 0.4064)
			(stroke
				(width 0.1524)
				(type default)
			)
			(layer "F.SilkS")
		)
		(fp_line
			(start -0.7874 0.4064)
			(end -0.7874 -0.4064)
			(stroke
				(width 0.1524)
				(type default)
			)
			(layer "F.SilkS")
		)
		(fp_line
			(start -0.12065 -0.305054)
			(end -0.12065 -0.2794)
			(stroke
				(width 0.1)
				(type default)
			)
			(layer "F.Fab")
		)
		(fp_line
			(start -0.67945 -0.305054)
			(end -0.12065 -0.305054)
			(stroke
				(width 0.1)
				(type default)
			)
			(layer "F.Fab")
		)
		(fp_line
			(start 0.67945 -0.3048)
			(end 0.67945 0.3048)
			(stroke
				(width 0.1)
				(type default)
			)
			(layer "F.Fab")
		)
		(fp_line
			(start 0.12065 -0.3048)
			(end 0.67945 -0.3048)
			(stroke
				(width 0.1)
				(type default)
			)
			(layer "F.Fab")
		)
		(fp_line
			(start 0.12065 -0.2794)
			(end 0.12065 -0.3048)
			(stroke
				(width 0.1)
				(type default)
			)
			(layer "F.Fab")
		)
		(fp_line
			(start -0.12065 -0.2794)
			(end 0.12065 -0.2794)
			(stroke
				(width 0.1)
				(type default)
			)
			(layer "F.Fab")
		)
		(fp_line
			(start 0.120396 0.2794)
			(end -0.12065 0.2794)
			(stroke
				(width 0.1)
				(type default)
			)
			(layer "F.Fab")
		)
		(fp_line
			(start -0.12065 0.2794)
			(end -0.12065 0.3048)
			(stroke
				(width 0.1)
				(type default)
			)
			(layer "F.Fab")
		)
		(fp_line
			(start 0.67945 0.3048)
			(end 0.120396 0.3048)
			(stroke
				(width 0.1)
				(type default)
			)
			(layer "F.Fab")
		)
		(fp_line
			(start 0.120396 0.3048)
			(end 0.120396 0.2794)
			(stroke
				(width 0.1)
				(type default)
			)
			(layer "F.Fab")
		)
		(fp_line
			(start -0.12065 0.3048)
			(end -0.67945 0.3048)
			(stroke
				(width 0.1)
				(type default)
			)
			(layer "F.Fab")
		)
		(fp_line
			(start -0.67945 0.3048)
			(end -0.67945 -0.305054)
			(stroke
				(width 0.1)
				(type default)
			)
			(layer "F.Fab")
		)
		(pad "1" smd circle
			(at -0.40005 0 90)
			(size 0 0)
			(layers "F.Cu" "F.Mask" "F.Paste")
			(net "P12V_OCP_SS_2")
		)
		(pad "2" smd circle
			(at 0.40005 0 90)
			(size 0 0)
			(layers "F.Cu" "F.Mask" "F.Paste")
			(net "GND")
		)
	)
)
